(kicad_pcb
	(version 20260206)
	(generator "pcbnew")
	(generator_version "10.0")
	(general
		(thickness 1.6)
		(legacy_teardrops no)
	)
	(paper "A4")
	(title_block
		(title "03242023_DA0F0TMBIJ0_F0T_Motherboard_J_brd_V01_OCP.brd")
		(comment 1 "Grand Teton / footprint 3039 of 6105 (U2), pads 3348-3459 of 4677")
	)
	(layers
		(0 "F.Cu" signal "TOP")
		(4 "In1.Cu" signal "GND")
		(6 "In2.Cu" signal "IN1")
		(8 "In3.Cu" signal "GND1")
		(10 "In4.Cu" signal "IN2")
		(12 "In5.Cu" signal "GND2")
		(14 "In6.Cu" signal "IN3")
		(16 "In7.Cu" signal "GND3")
		(18 "In8.Cu" signal "VCC")
		(20 "In9.Cu" signal "VCC1")
		(22 "In10.Cu" signal "GND4")
		(24 "In11.Cu" signal "IN4")
		(26 "In12.Cu" signal "GND5")
		(28 "In13.Cu" signal "IN5")
		(30 "In14.Cu" signal "GND6")
		(32 "In15.Cu" signal "IN6")
		(34 "In16.Cu" signal "GND7")
		(2 "B.Cu" signal "BOTTOM")
		(9 "F.Adhes" user "F.Adhesive")
		(11 "B.Adhes" user "B.Adhesive")
		(13 "F.Paste" user "Package Geometry/Pastemask Top")
		(15 "B.Paste" user "Package Geometry/Pastemask Bottom")
		(5 "F.SilkS" user "Ref Des/Silkscreen Top")
		(7 "B.SilkS" user "Ref Des/Silkscreen Bottom")
		(1 "F.Mask" user "Board Geometry/Soldermask Top")
		(3 "B.Mask" user "Board Geometry/Soldermask Bottom")
		(17 "Dwgs.User" user "User.Drawings")
		(19 "Cmts.User" user "User.Comments")
		(21 "Eco1.User" user "User.Eco1")
		(23 "Eco2.User" user "User.Eco2")
		(25 "Edge.Cuts" user "Board Geometry/Outline")
		(27 "Margin" user)
		(31 "F.CrtYd" user "Package Geometry/Place Bound Top")
		(29 "B.CrtYd" user "Package Geometry/Place Bound Bottom")
		(35 "F.Fab" user "Ref Des/Assembly Top")
		(33 "B.Fab" user "Ref Des/Assembly Bottom")
	)
	(footprint ""
		(layer "F.Cu")
		(at 359.870248 -251.76988 90)
		(property "Reference" "U2"
			(at -74.416158 -44.488608 0)
			(unlocked yes)
			(layer "F.SilkS")
			(effects
				(font
					(size 1.6002 1.1938)
					(thickness 0.1524)
				)
				(justify left)
			)
		)
		(property "Value" ""
			(at 0 0 90)
			(layer "F.Fab")
			(effects
				(font
					(size 1.27 1.27)
				)
			)
		)
		(duplicate_pad_numbers_are_jumpers no)
		(pad "EA31" smd circle
			(at -13.008356 19.915886 270)
			(size 0.4318 0.4318)
			(layers "F.Cu" "F.Mask" "F.Paste")
			(net "M_F_CPU0_SB_DQ<3>")
		)
		(pad "EA33" smd circle
			(at -11.380724 19.915886 270)
			(size 0.4318 0.4318)
			(layers "F.Cu" "F.Mask" "F.Paste")
			(net "GND")
		)
		(pad "EA35" smd circle
			(at -9.752838 19.915886 270)
			(size 0.4318 0.4318)
			(layers "F.Cu" "F.Mask" "F.Paste")
			(net "M_G_CPU0_SB_CB<2>")
		)
		(pad "EA37" smd circle
			(at -8.124952 19.915886 270)
			(size 0.4318 0.4318)
			(layers "F.Cu" "F.Mask" "F.Paste")
			(net "M_G_CPU0_SB_CB<7>")
		)
		(pad "EA39" smd circle
			(at -6.49732 19.915886 270)
			(size 0.4318 0.4318)
			(layers "F.Cu" "F.Mask" "F.Paste")
			(net "GND")
		)
		(pad "EA41" smd circle
			(at -4.869434 19.915886 270)
			(size 0.4318 0.4318)
			(layers "F.Cu" "F.Mask" "F.Paste")
			(net "M_G_CPU0_SB_CS_N<0>")
		)
		(pad "EA43" smd circle
			(at -3.241802 19.915886 270)
			(size 0.4318 0.4318)
			(layers "F.Cu" "F.Mask" "F.Paste")
			(net "M_G_CPU0_SB_CA<5>")
		)
		(pad "EA45" smd circle
			(at -1.613916 19.915886 270)
			(size 0.4318 0.4318)
			(layers "F.Cu" "F.Mask" "F.Paste")
			(net "GND")
		)
		(pad "EA48" smd circle
			(at 2.427732 20.025868 270)
			(size 0.4318 0.4318)
			(layers "F.Cu" "F.Mask" "F.Paste")
			(net "M_G_CPU0_SA_RSP<0>")
		)
		(pad "EA50" smd circle
			(at 4.055618 20.025868 270)
			(size 0.4318 0.4318)
			(layers "F.Cu" "F.Mask" "F.Paste")
			(net "M_F_CPU0_SA_PAR")
		)
		(pad "EA52" smd circle
			(at 5.68325 20.025868 270)
			(size 0.4318 0.4318)
			(layers "F.Cu" "F.Mask" "F.Paste")
			(net "GND")
		)
		(pad "EA54" smd circle
			(at 7.311136 20.025868 270)
			(size 0.4318 0.4318)
			(layers "F.Cu" "F.Mask" "F.Paste")
			(net "M_F_CPU0_SA_DQ<30>")
		)
		(pad "EA56" smd circle
			(at 8.939022 20.025868 270)
			(size 0.4318 0.4318)
			(layers "F.Cu" "F.Mask" "F.Paste")
			(net "M_F_CPU0_SA_DQ<27>")
		)
		(pad "EA58" smd circle
			(at 10.566654 20.025868 270)
			(size 0.4318 0.4318)
			(layers "F.Cu" "F.Mask" "F.Paste")
			(net "GND")
		)
		(pad "EA60" smd circle
			(at 12.19454 20.025868 270)
			(size 0.4318 0.4318)
			(layers "F.Cu" "F.Mask" "F.Paste")
			(net "M_G_CPU0_SA_DQ<22>")
		)
		(pad "EA62" smd circle
			(at 13.822426 20.025868 270)
			(size 0.4318 0.4318)
			(layers "F.Cu" "F.Mask" "F.Paste")
			(net "M_G_CPU0_SA_DQ<19>")
		)
		(pad "EA64" smd circle
			(at 15.450058 20.025868 270)
			(size 0.4318 0.4318)
			(layers "F.Cu" "F.Mask" "F.Paste")
			(net "GND")
		)
		(pad "EA66" smd circle
			(at 17.07769 20.025868 270)
			(size 0.4318 0.4318)
			(layers "F.Cu" "F.Mask" "F.Paste")
			(net "M_F_CPU0_SA_DQ<14>")
		)
		(pad "EA68" smd circle
			(at 18.705576 20.025868 270)
			(size 0.4318 0.4318)
			(layers "F.Cu" "F.Mask" "F.Paste")
			(net "M_F_CPU0_SA_DQ<11>")
		)
		(pad "EA70" smd circle
			(at 20.333462 20.025868 270)
			(size 0.4318 0.4318)
			(layers "F.Cu" "F.Mask" "F.Paste")
			(net "GND")
		)
		(pad "EA72" smd circle
			(at 21.961094 20.025868 270)
			(size 0.4318 0.4318)
			(layers "F.Cu" "F.Mask" "F.Paste")
			(net "M_G_CPU0_SA_DQ<6>")
		)
		(pad "EA74" smd circle
			(at 23.58898 20.025868 270)
			(size 0.4318 0.4318)
			(layers "F.Cu" "F.Mask" "F.Paste")
			(net "M_G_CPU0_SA_DQ<3>")
		)
		(pad "EA76" smd circle
			(at 25.216612 20.025868 270)
			(size 0.4318 0.4318)
			(layers "F.Cu" "F.Mask" "F.Paste")
			(net "GND")
		)
		(pad "EA78" smd circle
			(at 26.844498 20.025868 270)
			(size 0.4318 0.4318)
			(layers "F.Cu" "F.Mask" "F.Paste")
			(net "GND")
		)
		(pad "EA80" smd circle
			(at 28.472384 20.025868 270)
			(size 0.4318 0.4318)
			(layers "F.Cu" "F.Mask" "F.Paste")
			(net "GND")
		)
		(pad "EA82" smd circle
			(at 30.100016 20.025868 270)
			(size 0.4318 0.4318)
			(layers "F.Cu" "F.Mask" "F.Paste")
			(net "GND")
		)
		(pad "EA84" smd circle
			(at 31.727902 20.025868 270)
			(size 0.4318 0.4318)
			(layers "F.Cu" "F.Mask" "F.Paste")
			(net "GND")
		)
		(pad "EA86" smd circle
			(at 33.355534 20.025868 270)
			(size 0.4318 0.4318)
			(layers "F.Cu" "F.Mask" "F.Paste")
			(net "P5E_CPU0_PE3_TX_DP<2>")
		)
		(pad "EA88" smd circle
			(at 34.98342 20.025868 270)
			(size 0.4318 0.4318)
			(layers "F.Cu" "F.Mask" "F.Paste")
			(net "GND")
		)
		(pad "EA90" smd circle
			(at 36.611306 20.025868 270)
			(size 0.4318 0.4318)
			(layers "F.Cu" "F.Mask" "F.Paste")
			(net "P5E_CPU0_PE3_RX_DP<3>")
		)
		(pad "EB2" smd circle
			(at -36.611306 20.385532 270)
			(size 0.4318 0.4318)
			(layers "F.Cu" "F.Mask" "F.Paste")
			(net "UPI_CPU1_CPU0_P0P1_DP<3>")
		)
		(pad "EB4" smd circle
			(at -34.98342 20.385532 270)
			(size 0.4318 0.4318)
			(layers "F.Cu" "F.Mask" "F.Paste")
			(net "GND")
		)
		(pad "EB6" smd circle
			(at -33.355534 20.385532 270)
			(size 0.4318 0.4318)
			(layers "F.Cu" "F.Mask" "F.Paste")
			(net "UPI_CPU0_CPU1_P1P0_DN<2>")
		)
		(pad "EB8" smd circle
			(at -31.727902 20.385532 270)
			(size 0.4318 0.4318)
			(layers "F.Cu" "F.Mask" "F.Paste")
			(net "GND")
		)
		(pad "EB10" smd circle
			(at -30.100016 20.385532 270)
			(size 0.4318 0.4318)
			(layers "F.Cu" "F.Mask" "F.Paste")
			(net "P5E_CPU0_PE2_RX_DP<12>")
		)
		(pad "EB12" smd circle
			(at -28.472384 20.385532 270)
			(size 0.4318 0.4318)
			(layers "F.Cu" "F.Mask" "F.Paste")
			(net "GND")
		)
		(pad "EB14" smd circle
			(at -26.844498 20.385532 270)
			(size 0.4318 0.4318)
			(layers "F.Cu" "F.Mask" "F.Paste")
			(net "P5E_CPU0_PE2_TX_DN<13>")
		)
		(pad "EB16" smd circle
			(at -25.216612 20.385532 270)
			(size 0.4318 0.4318)
			(layers "F.Cu" "F.Mask" "F.Paste")
			(net "GND")
		)
		(pad "EB18" smd circle
			(at -23.58898 20.385532 270)
			(size 0.4318 0.4318)
			(layers "F.Cu" "F.Mask" "F.Paste")
			(net "M_F_CPU0_SB_DQS_DP<8>")
		)
		(pad "EB20" smd circle
			(at -21.961094 20.385532 270)
			(size 0.4318 0.4318)
			(layers "F.Cu" "F.Mask" "F.Paste")
			(net "GND")
		)
		(pad "EB22" smd circle
			(at -20.333462 20.385532 270)
			(size 0.4318 0.4318)
			(layers "F.Cu" "F.Mask" "F.Paste")
			(net "GND")
		)
		(pad "EB24" smd circle
			(at -18.705576 20.385532 270)
			(size 0.4318 0.4318)
			(layers "F.Cu" "F.Mask" "F.Paste")
			(net "M_G_CPU0_SB_DQS_DN<7>")
		)
		(pad "EB26" smd circle
			(at -17.07769 20.385532 270)
			(size 0.4318 0.4318)
			(layers "F.Cu" "F.Mask" "F.Paste")
			(net "GND")
		)
		(pad "EB28" smd circle
			(at -15.450058 20.385532 270)
			(size 0.4318 0.4318)
			(layers "F.Cu" "F.Mask" "F.Paste")
			(net "GND")
		)
		(pad "EB30" smd circle
			(at -13.822426 20.385532 270)
			(size 0.4318 0.4318)
			(layers "F.Cu" "F.Mask" "F.Paste")
			(net "M_F_CPU0_SB_DQS_DN<5>")
		)
		(pad "EB32" smd circle
			(at -12.19454 20.385532 270)
			(size 0.4318 0.4318)
			(layers "F.Cu" "F.Mask" "F.Paste")
			(net "GND")
		)
		(pad "EB34" smd circle
			(at -10.566654 20.385532 270)
			(size 0.4318 0.4318)
			(layers "F.Cu" "F.Mask" "F.Paste")
			(net "GND")
		)
		(pad "EB36" smd circle
			(at -8.939022 20.385532 270)
			(size 0.4318 0.4318)
			(layers "F.Cu" "F.Mask" "F.Paste")
			(net "M_G_CPU0_SB_DQS_DN<4>")
		)
		(pad "EB38" smd circle
			(at -7.311136 20.385532 270)
			(size 0.4318 0.4318)
			(layers "F.Cu" "F.Mask" "F.Paste")
			(net "GND")
		)
		(pad "EB40" smd circle
			(at -5.68325 20.385532 270)
			(size 0.4318 0.4318)
			(layers "F.Cu" "F.Mask" "F.Paste")
			(net "GND")
		)
		(pad "EB42" smd circle
			(at -4.055618 20.385532 270)
			(size 0.4318 0.4318)
			(layers "F.Cu" "F.Mask" "F.Paste")
			(net "M_G_CPU0_SB_PAR")
		)
		(pad "EB44" smd circle
			(at -2.427732 20.385532 270)
			(size 0.4318 0.4318)
			(layers "F.Cu" "F.Mask" "F.Paste")
			(net "GND")
		)
		(pad "EB47" smd circle
			(at 1.613916 20.495514 270)
			(size 0.4318 0.4318)
			(layers "F.Cu" "F.Mask" "F.Paste")
			(net "GND")
		)
		(pad "EB49" smd circle
			(at 3.241802 20.495514 270)
			(size 0.4318 0.4318)
			(layers "F.Cu" "F.Mask" "F.Paste")
			(net "M_F_CPU0_CLK_DP<0>")
		)
		(pad "EB51" smd circle
			(at 4.869434 20.495514 270)
			(size 0.4318 0.4318)
			(layers "F.Cu" "F.Mask" "F.Paste")
			(net "GND")
		)
		(pad "EB53" smd circle
			(at 6.49732 20.495514 270)
			(size 0.4318 0.4318)
			(layers "F.Cu" "F.Mask" "F.Paste")
			(net "GND")
		)
		(pad "EB55" smd circle
			(at 8.124952 20.495514 270)
			(size 0.4318 0.4318)
			(layers "F.Cu" "F.Mask" "F.Paste")
			(net "M_F_CPU0_SA_DQS_DN<8>")
		)
		(pad "EB57" smd circle
			(at 9.752838 20.495514 270)
			(size 0.4318 0.4318)
			(layers "F.Cu" "F.Mask" "F.Paste")
			(net "GND")
		)
		(pad "EB59" smd circle
			(at 11.380724 20.495514 270)
			(size 0.4318 0.4318)
			(layers "F.Cu" "F.Mask" "F.Paste")
			(net "GND")
		)
		(pad "EB61" smd circle
			(at 13.008356 20.495514 270)
			(size 0.4318 0.4318)
			(layers "F.Cu" "F.Mask" "F.Paste")
			(net "M_G_CPU0_SA_DQS_DN<7>")
		)
		(pad "EB63" smd circle
			(at 14.635988 20.495514 270)
			(size 0.4318 0.4318)
			(layers "F.Cu" "F.Mask" "F.Paste")
			(net "GND")
		)
		(pad "EB65" smd circle
			(at 16.263874 20.495514 270)
			(size 0.4318 0.4318)
			(layers "F.Cu" "F.Mask" "F.Paste")
			(net "GND")
		)
		(pad "EB67" smd circle
			(at 17.89176 20.495514 270)
			(size 0.4318 0.4318)
			(layers "F.Cu" "F.Mask" "F.Paste")
			(net "M_F_CPU0_SA_DQS_DN<6>")
		)
		(pad "EB69" smd circle
			(at 19.519392 20.495514 270)
			(size 0.4318 0.4318)
			(layers "F.Cu" "F.Mask" "F.Paste")
			(net "GND")
		)
		(pad "EB71" smd circle
			(at 21.147278 20.495514 270)
			(size 0.4318 0.4318)
			(layers "F.Cu" "F.Mask" "F.Paste")
			(net "GND")
		)
		(pad "EB73" smd circle
			(at 22.77491 20.495514 270)
			(size 0.4318 0.4318)
			(layers "F.Cu" "F.Mask" "F.Paste")
			(net "M_G_CPU0_SA_DQS_DN<5>")
		)
		(pad "EB75" smd circle
			(at 24.402796 20.495514 270)
			(size 0.4318 0.4318)
			(layers "F.Cu" "F.Mask" "F.Paste")
			(net "GND")
		)
		(pad "EB77" smd circle
			(at 26.030682 20.495514 270)
			(size 0.4318 0.4318)
			(layers "F.Cu" "F.Mask" "F.Paste")
			(net "M_F_CPU0_SA_DQ<0>")
		)
		(pad "EB79" smd circle
			(at 27.658314 20.495514 270)
			(size 0.4318 0.4318)
			(layers "F.Cu" "F.Mask" "F.Paste")
			(net "GND")
		)
		(pad "EB81" smd circle
			(at 29.2862 20.495514 270)
			(size 0.4318 0.4318)
			(layers "F.Cu" "F.Mask" "F.Paste")
			(net "GND")
		)
		(pad "EB83" smd circle
			(at 30.914086 20.495514 270)
			(size 0.4318 0.4318)
			(layers "F.Cu" "F.Mask" "F.Paste")
			(net "GND")
		)
		(pad "EB85" smd circle
			(at 32.541718 20.495514 270)
			(size 0.4318 0.4318)
			(layers "F.Cu" "F.Mask" "F.Paste")
			(net "P5E_CPU0_PE3_TX_DN<1>")
		)
		(pad "EB87" smd circle
			(at 34.169604 20.495514 270)
			(size 0.4318 0.4318)
			(layers "F.Cu" "F.Mask" "F.Paste")
			(net "GND")
		)
		(pad "EB89" smd circle
			(at 35.797236 20.495514 270)
			(size 0.4318 0.4318)
			(layers "F.Cu" "F.Mask" "F.Paste")
			(net "P5E_CPU0_PE3_RX_DP<2>")
		)
		(pad "EB91" smd oval
			(at 37.425122 20.495514)
			(size 0.381 0.4826)
			(drill
				(offset 0 -0.0508)
			)
			(layers "F.Cu" "F.Mask" "F.Paste")
			(net "GND")
		)
		(pad "EC1" smd oval
			(at -37.425122 20.855686 180)
			(size 0.381 0.4826)
			(drill
				(offset 0 -0.0508)
			)
			(layers "F.Cu" "F.Mask" "F.Paste")
			(net "GND")
		)
		(pad "EC3" smd circle
			(at -35.797236 20.855686 270)
			(size 0.4318 0.4318)
			(layers "F.Cu" "F.Mask" "F.Paste")
			(net "UPI_CPU1_CPU0_P0P1_DN<2>")
		)
		(pad "EC5" smd circle
			(at -34.169604 20.855686 270)
			(size 0.4318 0.4318)
			(layers "F.Cu" "F.Mask" "F.Paste")
			(net "GND")
		)
		(pad "EC7" smd circle
			(at -32.541718 20.855686 270)
			(size 0.4318 0.4318)
			(layers "F.Cu" "F.Mask" "F.Paste")
			(net "UPI_CPU0_CPU1_P1P0_DN<1>")
		)
		(pad "EC9" smd circle
			(at -30.914086 20.855686 270)
			(size 0.4318 0.4318)
			(layers "F.Cu" "F.Mask" "F.Paste")
			(net "GND")
		)
		(pad "EC11" smd circle
			(at -29.2862 20.855686 270)
			(size 0.4318 0.4318)
			(layers "F.Cu" "F.Mask" "F.Paste")
			(net "P5E_CPU0_PE2_RX_DP<13>")
		)
		(pad "EC13" smd circle
			(at -27.658314 20.855686 270)
			(size 0.4318 0.4318)
			(layers "F.Cu" "F.Mask" "F.Paste")
			(net "GND")
		)
		(pad "EC15" smd circle
			(at -26.030682 20.855686 270)
			(size 0.4318 0.4318)
			(layers "F.Cu" "F.Mask" "F.Paste")
			(net "P5E_CPU0_PE2_TX_DP<13>")
		)
		(pad "EC17" smd circle
			(at -24.402796 20.855686 270)
			(size 0.4318 0.4318)
			(layers "F.Cu" "F.Mask" "F.Paste")
			(net "M_F_CPU0_SB_DQ<30>")
		)
		(pad "EC19" smd circle
			(at -22.77491 20.855686 270)
			(size 0.4318 0.4318)
			(layers "F.Cu" "F.Mask" "F.Paste")
			(net "GND")
		)
		(pad "EC21" smd circle
			(at -21.147278 20.855686 270)
			(size 0.4318 0.4318)
			(layers "F.Cu" "F.Mask" "F.Paste")
			(net "M_F_CPU0_SB_DQS_DP<1>")
		)
		(pad "EC23" smd circle
			(at -19.519392 20.855686 270)
			(size 0.4318 0.4318)
			(layers "F.Cu" "F.Mask" "F.Paste")
			(net "GND")
		)
		(pad "EC25" smd circle
			(at -17.89176 20.855686 270)
			(size 0.4318 0.4318)
			(layers "F.Cu" "F.Mask" "F.Paste")
			(net "GND")
		)
		(pad "EC27" smd circle
			(at -16.263874 20.855686 270)
			(size 0.4318 0.4318)
			(layers "F.Cu" "F.Mask" "F.Paste")
			(net "M_E_CPU0_SB_DQS_DP<0>")
		)
		(pad "EC29" smd circle
			(at -14.635988 20.855686 270)
			(size 0.4318 0.4318)
			(layers "F.Cu" "F.Mask" "F.Paste")
			(net "GND")
		)
		(pad "EC31" smd circle
			(at -13.008356 20.855686 270)
			(size 0.4318 0.4318)
			(layers "F.Cu" "F.Mask" "F.Paste")
			(net "GND")
		)
		(pad "EC33" smd circle
			(at -11.380724 20.855686 270)
			(size 0.4318 0.4318)
			(layers "F.Cu" "F.Mask" "F.Paste")
			(net "M_F_CPU0_SB_DQS_DP<9>")
		)
		(pad "EC35" smd circle
			(at -9.752838 20.855686 270)
			(size 0.4318 0.4318)
			(layers "F.Cu" "F.Mask" "F.Paste")
			(net "GND")
		)
		(pad "EC37" smd circle
			(at -8.124952 20.855686 270)
			(size 0.4318 0.4318)
			(layers "F.Cu" "F.Mask" "F.Paste")
			(net "GND")
		)
		(pad "EC39" smd circle
			(at -6.49732 20.855686 270)
			(size 0.4318 0.4318)
			(layers "F.Cu" "F.Mask" "F.Paste")
			(net "M_F_CPU0_SB_CA<6>")
		)
		(pad "EC41" smd circle
			(at -4.869434 20.855686 270)
			(size 0.4318 0.4318)
			(layers "F.Cu" "F.Mask" "F.Paste")
			(net "GND")
		)
		(pad "EC43" smd circle
			(at -3.241802 20.855686 270)
			(size 0.4318 0.4318)
			(layers "F.Cu" "F.Mask" "F.Paste")
			(net "GND")
		)
		(pad "EC45" smd circle
			(at -1.613916 20.855686 270)
			(size 0.4318 0.4318)
			(layers "F.Cu" "F.Mask" "F.Paste")
			(net "M_E_CPU0_CLK_DP<1>")
		)
		(pad "EC48" smd circle
			(at 2.427732 20.965668 270)
			(size 0.4318 0.4318)
			(layers "F.Cu" "F.Mask" "F.Paste")
			(net "GND")
		)
		(pad "EC50" smd circle
			(at 4.055618 20.965668 270)
			(size 0.4318 0.4318)
			(layers "F.Cu" "F.Mask" "F.Paste")
			(net "GND")
		)
		(pad "EC52" smd circle
			(at 5.68325 20.965668 270)
			(size 0.4318 0.4318)
			(layers "F.Cu" "F.Mask" "F.Paste")
			(net "M_F_CPU0_SA_CA<0>")
		)
		(pad "EC54" smd circle
			(at 7.311136 20.965668 270)
			(size 0.4318 0.4318)
			(layers "F.Cu" "F.Mask" "F.Paste")
			(net "GND")
		)
		(pad "EC56" smd circle
			(at 8.939022 20.965668 270)
			(size 0.4318 0.4318)
			(layers "F.Cu" "F.Mask" "F.Paste")
			(net "GND")
		)
		(pad "EC58" smd circle
			(at 10.566654 20.965668 270)
			(size 0.4318 0.4318)
			(layers "F.Cu" "F.Mask" "F.Paste")
			(net "M_F_CPU0_SA_DQS_DP<4>")
		)
		(pad "EC60" smd circle
			(at 12.19454 20.965668 270)
			(size 0.4318 0.4318)
			(layers "F.Cu" "F.Mask" "F.Paste")
			(net "GND")
		)
		(pad "EC62" smd circle
			(at 13.822426 20.965668 270)
			(size 0.4318 0.4318)
			(layers "F.Cu" "F.Mask" "F.Paste")
			(net "GND")
		)
		(pad "EC64" smd circle
			(at 15.450058 20.965668 270)
			(size 0.4318 0.4318)
			(layers "F.Cu" "F.Mask" "F.Paste")
			(net "M_F_CPU0_SA_DQS_DN<2>")
		)
		(pad "EC66" smd circle
			(at 17.07769 20.965668 270)
			(size 0.4318 0.4318)
			(layers "F.Cu" "F.Mask" "F.Paste")
			(net "GND")
		)
		(pad "EC68" smd circle
			(at 18.705576 20.965668 270)
			(size 0.4318 0.4318)
			(layers "F.Cu" "F.Mask" "F.Paste")
			(net "GND")
		)
		(pad "EC70" smd circle
			(at 20.333462 20.965668 270)
			(size 0.4318 0.4318)
			(layers "F.Cu" "F.Mask" "F.Paste")
			(net "M_E_CPU0_SA_DQS_DN<1>")
		)
		(pad "EC72" smd circle
			(at 21.961094 20.965668 270)
			(size 0.4318 0.4318)
			(layers "F.Cu" "F.Mask" "F.Paste")
			(net "GND")
		)
		(pad "EC74" smd circle
			(at 23.58898 20.965668 270)
			(size 0.4318 0.4318)
			(layers "F.Cu" "F.Mask" "F.Paste")
			(net "GND")
		)
	)
)
